FILE_TYPE = CONNECTIVITY;
{Allegro Design Entry HDL 17.2-2016 S081 (4005846) 1/11/2022}
"PAGE_NUMBER" = 210;
0"NC";
END.
